(kicad_pcb
	(version 20260206)
	(generator "pcbnew")
	(generator_version "10.0")
	(general
		(thickness 1.6)
		(legacy_teardrops no)
	)
	(paper "A4")
	(title_block
		(title "03242023_DA0F0TMBIJ0_F0T_Motherboard_J_brd_V01_OCP.brd")
		(comment 1 "Grand Teton / footprints 1155-1161 of 6105")
	)
	(layers
		(0 "F.Cu" signal "TOP")
		(4 "In1.Cu" signal "GND")
		(6 "In2.Cu" signal "IN1")
		(8 "In3.Cu" signal "GND1")
		(10 "In4.Cu" signal "IN2")
		(12 "In5.Cu" signal "GND2")
		(14 "In6.Cu" signal "IN3")
		(16 "In7.Cu" signal "GND3")
		(18 "In8.Cu" signal "VCC")
		(20 "In9.Cu" signal "VCC1")
		(22 "In10.Cu" signal "GND4")
		(24 "In11.Cu" signal "IN4")
		(26 "In12.Cu" signal "GND5")
		(28 "In13.Cu" signal "IN5")
		(30 "In14.Cu" signal "GND6")
		(32 "In15.Cu" signal "IN6")
		(34 "In16.Cu" signal "GND7")
		(2 "B.Cu" signal "BOTTOM")
		(9 "F.Adhes" user "F.Adhesive")
		(11 "B.Adhes" user "B.Adhesive")
		(13 "F.Paste" user "Package Geometry/Pastemask Top")
		(15 "B.Paste" user "Package Geometry/Pastemask Bottom")
		(5 "F.SilkS" user "Ref Des/Silkscreen Top")
		(7 "B.SilkS" user "Ref Des/Silkscreen Bottom")
		(1 "F.Mask" user "Board Geometry/Soldermask Top")
		(3 "B.Mask" user "Board Geometry/Soldermask Bottom")
		(17 "Dwgs.User" user "User.Drawings")
		(19 "Cmts.User" user "User.Comments")
		(21 "Eco1.User" user "User.Eco1")
		(23 "Eco2.User" user "User.Eco2")
		(25 "Edge.Cuts" user "Board Geometry/Outline")
		(27 "Margin" user)
		(31 "F.CrtYd" user "Package Geometry/Place Bound Top")
		(29 "B.CrtYd" user "Package Geometry/Place Bound Bottom")
		(35 "F.Fab" user "Ref Des/Assembly Top")
		(33 "B.Fab" user "Ref Des/Assembly Bottom")
	)
	(footprint ""
		(layer "F.Cu")
		(at 220.087444 -101.24948 180)
		(property "Reference" "R4806"
			(at 0 0 180)
			(layer "F.SilkS")
			(hide yes)
			(effects
				(font
					(size 1.27 1.27)
				)
			)
		)
		(property "Value" ""
			(at 0 0 180)
			(layer "F.Fab")
			(effects
				(font
					(size 1.27 1.27)
				)
			)
		)
		(duplicate_pad_numbers_are_jumpers no)
		(fp_line
			(start 0.7874 0.4064)
			(end -0.7874 0.4064)
			(stroke
				(width 0.1524)
				(type default)
			)
			(layer "F.SilkS")
		)
		(fp_line
			(start 0.7874 -0.4064)
			(end 0.7874 0.4064)
			(stroke
				(width 0.1524)
				(type default)
			)
			(layer "F.SilkS")
		)
		(fp_line
			(start -0.7874 0.4064)
			(end -0.7874 -0.4064)
			(stroke
				(width 0.1524)
				(type default)
			)
			(layer "F.SilkS")
		)
		(fp_line
			(start -0.7874 -0.4064)
			(end 0.7874 -0.4064)
			(stroke
				(width 0.1524)
				(type default)
			)
			(layer "F.SilkS")
		)
		(fp_line
			(start 0.67945 0.3048)
			(end 0.120396 0.3048)
			(stroke
				(width 0.1)
				(type default)
			)
			(layer "F.Fab")
		)
		(fp_line
			(start 0.67945 -0.3048)
			(end 0.67945 0.3048)
			(stroke
				(width 0.1)
				(type default)
			)
			(layer "F.Fab")
		)
		(fp_line
			(start 0.12065 -0.2794)
			(end 0.12065 -0.3048)
			(stroke
				(width 0.1)
				(type default)
			)
			(layer "F.Fab")
		)
		(fp_line
			(start 0.12065 -0.3048)
			(end 0.67945 -0.3048)
			(stroke
				(width 0.1)
				(type default)
			)
			(layer "F.Fab")
		)
		(fp_line
			(start 0.120396 0.3048)
			(end 0.120396 0.2794)
			(stroke
				(width 0.1)
				(type default)
			)
			(layer "F.Fab")
		)
		(fp_line
			(start 0.120396 0.2794)
			(end -0.12065 0.2794)
			(stroke
				(width 0.1)
				(type default)
			)
			(layer "F.Fab")
		)
		(fp_line
			(start -0.12065 0.3048)
			(end -0.67945 0.3048)
			(stroke
				(width 0.1)
				(type default)
			)
			(layer "F.Fab")
		)
		(fp_line
			(start -0.12065 0.2794)
			(end -0.12065 0.3048)
			(stroke
				(width 0.1)
				(type default)
			)
			(layer "F.Fab")
		)
		(fp_line
			(start -0.12065 -0.2794)
			(end 0.12065 -0.2794)
			(stroke
				(width 0.1)
				(type default)
			)
			(layer "F.Fab")
		)
		(fp_line
			(start -0.12065 -0.305054)
			(end -0.12065 -0.2794)
			(stroke
				(width 0.1)
				(type default)
			)
			(layer "F.Fab")
		)
		(fp_line
			(start -0.67945 0.3048)
			(end -0.67945 -0.305054)
			(stroke
				(width 0.1)
				(type default)
			)
			(layer "F.Fab")
		)
		(fp_line
			(start -0.67945 -0.305054)
			(end -0.12065 -0.305054)
			(stroke
				(width 0.1)
				(type default)
			)
			(layer "F.Fab")
		)
		(pad "1" smd circle
			(at -0.40005 0 180)
			(size 0 0)
			(layers "F.Cu" "F.Mask" "F.Paste")
			(net "P12V_AUX")
		)
		(pad "2" smd circle
			(at 0.40005 0 180)
			(size 0 0)
			(layers "F.Cu" "F.Mask" "F.Paste")
			(net "U206_VDD")
		)
	)
	(footprint ""
		(layer "F.Cu")
		(at 307.3908 -23.7744 180)
		(property "Reference" "C2385"
			(at 0 0 180)
			(layer "F.SilkS")
			(hide yes)
			(effects
				(font
					(size 1.27 1.27)
				)
			)
		)
		(property "Value" ""
			(at 0 0 180)
			(layer "F.Fab")
			(effects
				(font
					(size 1.27 1.27)
				)
			)
		)
		(duplicate_pad_numbers_are_jumpers no)
		(fp_line
			(start 0.7874 0.4064)
			(end -0.7874 0.4064)
			(stroke
				(width 0.1524)
				(type default)
			)
			(layer "F.SilkS")
		)
		(fp_line
			(start 0.7874 -0.4064)
			(end 0.7874 0.4064)
			(stroke
				(width 0.1524)
				(type default)
			)
			(layer "F.SilkS")
		)
		(fp_line
			(start -0.7874 0.4064)
			(end -0.7874 -0.4064)
			(stroke
				(width 0.1524)
				(type default)
			)
			(layer "F.SilkS")
		)
		(fp_line
			(start -0.7874 -0.4064)
			(end 0.7874 -0.4064)
			(stroke
				(width 0.1524)
				(type default)
			)
			(layer "F.SilkS")
		)
		(fp_line
			(start 0.67945 0.3048)
			(end 0.120396 0.3048)
			(stroke
				(width 0.1)
				(type default)
			)
			(layer "F.Fab")
		)
		(fp_line
			(start 0.67945 -0.3048)
			(end 0.67945 0.3048)
			(stroke
				(width 0.1)
				(type default)
			)
			(layer "F.Fab")
		)
		(fp_line
			(start 0.12065 -0.2794)
			(end 0.12065 -0.3048)
			(stroke
				(width 0.1)
				(type default)
			)
			(layer "F.Fab")
		)
		(fp_line
			(start 0.12065 -0.3048)
			(end 0.67945 -0.3048)
			(stroke
				(width 0.1)
				(type default)
			)
			(layer "F.Fab")
		)
		(fp_line
			(start 0.120396 0.3048)
			(end 0.120396 0.2794)
			(stroke
				(width 0.1)
				(type default)
			)
			(layer "F.Fab")
		)
		(fp_line
			(start 0.120396 0.2794)
			(end -0.12065 0.2794)
			(stroke
				(width 0.1)
				(type default)
			)
			(layer "F.Fab")
		)
		(fp_line
			(start -0.12065 0.3048)
			(end -0.67945 0.3048)
			(stroke
				(width 0.1)
				(type default)
			)
			(layer "F.Fab")
		)
		(fp_line
			(start -0.12065 0.2794)
			(end -0.12065 0.3048)
			(stroke
				(width 0.1)
				(type default)
			)
			(layer "F.Fab")
		)
		(fp_line
			(start -0.12065 -0.2794)
			(end 0.12065 -0.2794)
			(stroke
				(width 0.1)
				(type default)
			)
			(layer "F.Fab")
		)
		(fp_line
			(start -0.12065 -0.305054)
			(end -0.12065 -0.2794)
			(stroke
				(width 0.1)
				(type default)
			)
			(layer "F.Fab")
		)
		(fp_line
			(start -0.67945 0.3048)
			(end -0.67945 -0.305054)
			(stroke
				(width 0.1)
				(type default)
			)
			(layer "F.Fab")
		)
		(fp_line
			(start -0.67945 -0.305054)
			(end -0.12065 -0.305054)
			(stroke
				(width 0.1)
				(type default)
			)
			(layer "F.Fab")
		)
		(pad "1" smd circle
			(at -0.40005 0 180)
			(size 0 0)
			(layers "F.Cu" "F.Mask" "F.Paste")
			(net "DSW_PWROK_P2V5_COMP")
		)
		(pad "2" smd circle
			(at 0.40005 0 180)
			(size 0 0)
			(layers "F.Cu" "F.Mask" "F.Paste")
			(net "GND")
		)
	)
	(footprint ""
		(layer "F.Cu")
		(at 303.65573 -345.347544 180)
		(property "Reference" "PR586"
			(at 0 0 180)
			(layer "F.SilkS")
			(hide yes)
			(effects
				(font
					(size 1.27 1.27)
				)
			)
		)
		(property "Value" ""
			(at 0 0 180)
			(layer "F.Fab")
			(effects
				(font
					(size 1.27 1.27)
				)
			)
		)
		(duplicate_pad_numbers_are_jumpers no)
		(fp_line
			(start 0.7874 0.4064)
			(end -0.7874 0.4064)
			(stroke
				(width 0.1524)
				(type default)
			)
			(layer "F.SilkS")
		)
		(fp_line
			(start 0.7874 -0.4064)
			(end 0.7874 0.4064)
			(stroke
				(width 0.1524)
				(type default)
			)
			(layer "F.SilkS")
		)
		(fp_line
			(start -0.7874 0.4064)
			(end -0.7874 -0.4064)
			(stroke
				(width 0.1524)
				(type default)
			)
			(layer "F.SilkS")
		)
		(fp_line
			(start -0.7874 -0.4064)
			(end 0.7874 -0.4064)
			(stroke
				(width 0.1524)
				(type default)
			)
			(layer "F.SilkS")
		)
		(fp_line
			(start 0.67945 0.3048)
			(end 0.120396 0.3048)
			(stroke
				(width 0.1)
				(type default)
			)
			(layer "F.Fab")
		)
		(fp_line
			(start 0.67945 -0.3048)
			(end 0.67945 0.3048)
			(stroke
				(width 0.1)
				(type default)
			)
			(layer "F.Fab")
		)
		(fp_line
			(start 0.12065 -0.2794)
			(end 0.12065 -0.3048)
			(stroke
				(width 0.1)
				(type default)
			)
			(layer "F.Fab")
		)
		(fp_line
			(start 0.12065 -0.3048)
			(end 0.67945 -0.3048)
			(stroke
				(width 0.1)
				(type default)
			)
			(layer "F.Fab")
		)
		(fp_line
			(start 0.120396 0.3048)
			(end 0.120396 0.2794)
			(stroke
				(width 0.1)
				(type default)
			)
			(layer "F.Fab")
		)
		(fp_line
			(start 0.120396 0.2794)
			(end -0.12065 0.2794)
			(stroke
				(width 0.1)
				(type default)
			)
			(layer "F.Fab")
		)
		(fp_line
			(start -0.12065 0.3048)
			(end -0.67945 0.3048)
			(stroke
				(width 0.1)
				(type default)
			)
			(layer "F.Fab")
		)
		(fp_line
			(start -0.12065 0.2794)
			(end -0.12065 0.3048)
			(stroke
				(width 0.1)
				(type default)
			)
			(layer "F.Fab")
		)
		(fp_line
			(start -0.12065 -0.2794)
			(end 0.12065 -0.2794)
			(stroke
				(width 0.1)
				(type default)
			)
			(layer "F.Fab")
		)
		(fp_line
			(start -0.12065 -0.305054)
			(end -0.12065 -0.2794)
			(stroke
				(width 0.1)
				(type default)
			)
			(layer "F.Fab")
		)
		(fp_line
			(start -0.67945 0.3048)
			(end -0.67945 -0.305054)
			(stroke
				(width 0.1)
				(type default)
			)
			(layer "F.Fab")
		)
		(fp_line
			(start -0.67945 -0.305054)
			(end -0.12065 -0.305054)
			(stroke
				(width 0.1)
				(type default)
			)
			(layer "F.Fab")
		)
		(pad "1" smd circle
			(at -0.40005 0 180)
			(size 0 0)
			(layers "F.Cu" "F.Mask" "F.Paste")
			(net "VSENSE_PVCCFA_EHV_FIVRA_CPU0_DN")
		)
		(pad "2" smd circle
			(at 0.40005 0 180)
			(size 0 0)
			(layers "F.Cu" "F.Mask" "F.Paste")
			(net "GND")
		)
	)
	(footprint ""
		(layer "F.Cu")
		(at 108.85043 -401.184364)
		(property "Reference" "R3490"
			(at 0 0 0)
			(layer "F.SilkS")
			(hide yes)
			(effects
				(font
					(size 1.27 1.27)
				)
			)
		)
		(property "Value" ""
			(at 0 0 0)
			(layer "F.Fab")
			(effects
				(font
					(size 1.27 1.27)
				)
			)
		)
		(duplicate_pad_numbers_are_jumpers no)
		(fp_line
			(start -0.7874 -0.4064)
			(end 0.7874 -0.4064)
			(stroke
				(width 0.1524)
				(type default)
			)
			(layer "F.SilkS")
		)
		(fp_line
			(start -0.7874 0.4064)
			(end -0.7874 -0.4064)
			(stroke
				(width 0.1524)
				(type default)
			)
			(layer "F.SilkS")
		)
		(fp_line
			(start 0.7874 -0.4064)
			(end 0.7874 0.4064)
			(stroke
				(width 0.1524)
				(type default)
			)
			(layer "F.SilkS")
		)
		(fp_line
			(start 0.7874 0.4064)
			(end -0.7874 0.4064)
			(stroke
				(width 0.1524)
				(type default)
			)
			(layer "F.SilkS")
		)
		(fp_line
			(start -0.67945 -0.305054)
			(end -0.12065 -0.305054)
			(stroke
				(width 0.1)
				(type default)
			)
			(layer "F.Fab")
		)
		(fp_line
			(start -0.67945 0.3048)
			(end -0.67945 -0.305054)
			(stroke
				(width 0.1)
				(type default)
			)
			(layer "F.Fab")
		)
		(fp_line
			(start -0.12065 -0.305054)
			(end -0.12065 -0.2794)
			(stroke
				(width 0.1)
				(type default)
			)
			(layer "F.Fab")
		)
		(fp_line
			(start -0.12065 -0.2794)
			(end 0.12065 -0.2794)
			(stroke
				(width 0.1)
				(type default)
			)
			(layer "F.Fab")
		)
		(fp_line
			(start -0.12065 0.2794)
			(end -0.12065 0.3048)
			(stroke
				(width 0.1)
				(type default)
			)
			(layer "F.Fab")
		)
		(fp_line
			(start -0.12065 0.3048)
			(end -0.67945 0.3048)
			(stroke
				(width 0.1)
				(type default)
			)
			(layer "F.Fab")
		)
		(fp_line
			(start 0.120396 0.2794)
			(end -0.12065 0.2794)
			(stroke
				(width 0.1)
				(type default)
			)
			(layer "F.Fab")
		)
		(fp_line
			(start 0.120396 0.3048)
			(end 0.120396 0.2794)
			(stroke
				(width 0.1)
				(type default)
			)
			(layer "F.Fab")
		)
		(fp_line
			(start 0.12065 -0.3048)
			(end 0.67945 -0.3048)
			(stroke
				(width 0.1)
				(type default)
			)
			(layer "F.Fab")
		)
		(fp_line
			(start 0.12065 -0.2794)
			(end 0.12065 -0.3048)
			(stroke
				(width 0.1)
				(type default)
			)
			(layer "F.Fab")
		)
		(fp_line
			(start 0.67945 -0.3048)
			(end 0.67945 0.3048)
			(stroke
				(width 0.1)
				(type default)
			)
			(layer "F.Fab")
		)
		(fp_line
			(start 0.67945 0.3048)
			(end 0.120396 0.3048)
			(stroke
				(width 0.1)
				(type default)
			)
			(layer "F.Fab")
		)
		(pad "1" smd circle
			(at -0.40005 0)
			(size 0 0)
			(layers "F.Cu" "F.Mask" "F.Paste")
			(net "P3V3_AUX")
		)
		(pad "2" smd circle
			(at 0.40005 0)
			(size 0 0)
			(layers "F.Cu" "F.Mask" "F.Paste")
			(net "GPU_FPGA_EROT_RECOV_N")
		)
	)
	(footprint ""
		(layer "F.Cu")
		(at 104.503728 -426.787818)
		(property "Reference" "R4210"
			(at 0 0 0)
			(layer "F.SilkS")
			(hide yes)
			(effects
				(font
					(size 1.27 1.27)
				)
			)
		)
		(property "Value" ""
			(at 0 0 0)
			(layer "F.Fab")
			(effects
				(font
					(size 1.27 1.27)
				)
			)
		)
		(duplicate_pad_numbers_are_jumpers no)
		(fp_line
			(start -0.7874 -0.4064)
			(end 0.7874 -0.4064)
			(stroke
				(width 0.1524)
				(type default)
			)
			(layer "F.SilkS")
		)
		(fp_line
			(start -0.7874 0.4064)
			(end -0.7874 -0.4064)
			(stroke
				(width 0.1524)
				(type default)
			)
			(layer "F.SilkS")
		)
		(fp_line
			(start 0.7874 -0.4064)
			(end 0.7874 0.4064)
			(stroke
				(width 0.1524)
				(type default)
			)
			(layer "F.SilkS")
		)
		(fp_line
			(start 0.7874 0.4064)
			(end -0.7874 0.4064)
			(stroke
				(width 0.1524)
				(type default)
			)
			(layer "F.SilkS")
		)
		(fp_line
			(start -0.67945 -0.305054)
			(end -0.12065 -0.305054)
			(stroke
				(width 0.1)
				(type default)
			)
			(layer "F.Fab")
		)
		(fp_line
			(start -0.67945 0.3048)
			(end -0.67945 -0.305054)
			(stroke
				(width 0.1)
				(type default)
			)
			(layer "F.Fab")
		)
		(fp_line
			(start -0.12065 -0.305054)
			(end -0.12065 -0.2794)
			(stroke
				(width 0.1)
				(type default)
			)
			(layer "F.Fab")
		)
		(fp_line
			(start -0.12065 -0.2794)
			(end 0.12065 -0.2794)
			(stroke
				(width 0.1)
				(type default)
			)
			(layer "F.Fab")
		)
		(fp_line
			(start -0.12065 0.2794)
			(end -0.12065 0.3048)
			(stroke
				(width 0.1)
				(type default)
			)
			(layer "F.Fab")
		)
		(fp_line
			(start -0.12065 0.3048)
			(end -0.67945 0.3048)
			(stroke
				(width 0.1)
				(type default)
			)
			(layer "F.Fab")
		)
		(fp_line
			(start 0.120396 0.2794)
			(end -0.12065 0.2794)
			(stroke
				(width 0.1)
				(type default)
			)
			(layer "F.Fab")
		)
		(fp_line
			(start 0.120396 0.3048)
			(end 0.120396 0.2794)
			(stroke
				(width 0.1)
				(type default)
			)
			(layer "F.Fab")
		)
		(fp_line
			(start 0.12065 -0.3048)
			(end 0.67945 -0.3048)
			(stroke
				(width 0.1)
				(type default)
			)
			(layer "F.Fab")
		)
		(fp_line
			(start 0.12065 -0.2794)
			(end 0.12065 -0.3048)
			(stroke
				(width 0.1)
				(type default)
			)
			(layer "F.Fab")
		)
		(fp_line
			(start 0.67945 -0.3048)
			(end 0.67945 0.3048)
			(stroke
				(width 0.1)
				(type default)
			)
			(layer "F.Fab")
		)
		(fp_line
			(start 0.67945 0.3048)
			(end 0.120396 0.3048)
			(stroke
				(width 0.1)
				(type default)
			)
			(layer "F.Fab")
		)
		(pad "1" smd circle
			(at -0.40005 0)
			(size 0 0)
			(layers "F.Cu" "F.Mask" "F.Paste")
			(net "P3V3_AUX")
		)
		(pad "2" smd circle
			(at 0.40005 0)
			(size 0 0)
			(layers "F.Cu" "F.Mask" "F.Paste")
			(net "FM_THERMAL_ALERT_N")
		)
	)
	(footprint ""
		(layer "F.Cu")
		(at 388.05993 -408.517344 -90)
		(property "Reference" "C880"
			(at 0 0 270)
			(layer "F.SilkS")
			(hide yes)
			(effects
				(font
					(size 1.27 1.27)
				)
			)
		)
		(property "Value" ""
			(at 0 0 270)
			(layer "F.Fab")
			(effects
				(font
					(size 1.27 1.27)
				)
			)
		)
		(duplicate_pad_numbers_are_jumpers no)
		(fp_line
			(start -0.299974 0.150114)
			(end -0.299974 -0.150114)
			(stroke
				(width 0.1)
				(type default)
			)
			(layer "F.Fab")
		)
		(fp_line
			(start 0.299974 0.150114)
			(end -0.299974 0.150114)
			(stroke
				(width 0.1)
				(type default)
			)
			(layer "F.Fab")
		)
		(fp_line
			(start -0.299974 -0.150114)
			(end 0.299974 -0.150114)
			(stroke
				(width 0.1)
				(type default)
			)
			(layer "F.Fab")
		)
		(fp_line
			(start 0.299974 -0.150114)
			(end 0.299974 0.150114)
			(stroke
				(width 0.1)
				(type default)
			)
			(layer "F.Fab")
		)
		(pad "1" smd rect
			(at -0.2667 0 270)
			(size 0.3048 0.381)
			(layers "F.Cu" "F.Mask" "F.Paste")
			(net "P5E_CPU0_PE3_TX_C_DN<10>")
		)
		(pad "2" smd rect
			(at 0.2667 0 270)
			(size 0.3048 0.381)
			(layers "F.Cu" "F.Mask" "F.Paste")
			(net "P5E_CPU0_PE3_TX_DN<10>")
		)
	)
	(footprint ""
		(layer "F.Cu")
		(at 108.85043 -402.200364 180)
		(property "Reference" "R3491"
			(at 0 0 180)
			(layer "F.SilkS")
			(hide yes)
			(effects
				(font
					(size 1.27 1.27)
				)
			)
		)
		(property "Value" ""
			(at 0 0 180)
			(layer "F.Fab")
			(effects
				(font
					(size 1.27 1.27)
				)
			)
		)
		(duplicate_pad_numbers_are_jumpers no)
		(fp_line
			(start 0.7874 0.4064)
			(end -0.7874 0.4064)
			(stroke
				(width 0.1524)
				(type default)
			)
			(layer "F.SilkS")
		)
		(fp_line
			(start 0.7874 -0.4064)
			(end 0.7874 0.4064)
			(stroke
				(width 0.1524)
				(type default)
			)
			(layer "F.SilkS")
		)
		(fp_line
			(start -0.7874 0.4064)
			(end -0.7874 -0.4064)
			(stroke
				(width 0.1524)
				(type default)
			)
			(layer "F.SilkS")
		)
		(fp_line
			(start -0.7874 -0.4064)
			(end 0.7874 -0.4064)
			(stroke
				(width 0.1524)
				(type default)
			)
			(layer "F.SilkS")
		)
		(fp_line
			(start 0.67945 0.3048)
			(end 0.120396 0.3048)
			(stroke
				(width 0.1)
				(type default)
			)
			(layer "F.Fab")
		)
		(fp_line
			(start 0.67945 -0.3048)
			(end 0.67945 0.3048)
			(stroke
				(width 0.1)
				(type default)
			)
			(layer "F.Fab")
		)
		(fp_line
			(start 0.12065 -0.2794)
			(end 0.12065 -0.3048)
			(stroke
				(width 0.1)
				(type default)
			)
			(layer "F.Fab")
		)
		(fp_line
			(start 0.12065 -0.3048)
			(end 0.67945 -0.3048)
			(stroke
				(width 0.1)
				(type default)
			)
			(layer "F.Fab")
		)
		(fp_line
			(start 0.120396 0.3048)
			(end 0.120396 0.2794)
			(stroke
				(width 0.1)
				(type default)
			)
			(layer "F.Fab")
		)
		(fp_line
			(start 0.120396 0.2794)
			(end -0.12065 0.2794)
			(stroke
				(width 0.1)
				(type default)
			)
			(layer "F.Fab")
		)
		(fp_line
			(start -0.12065 0.3048)
			(end -0.67945 0.3048)
			(stroke
				(width 0.1)
				(type default)
			)
			(layer "F.Fab")
		)
		(fp_line
			(start -0.12065 0.2794)
			(end -0.12065 0.3048)
			(stroke
				(width 0.1)
				(type default)
			)
			(layer "F.Fab")
		)
		(fp_line
			(start -0.12065 -0.2794)
			(end 0.12065 -0.2794)
			(stroke
				(width 0.1)
				(type default)
			)
			(layer "F.Fab")
		)
		(fp_line
			(start -0.12065 -0.305054)
			(end -0.12065 -0.2794)
			(stroke
				(width 0.1)
				(type default)
			)
			(layer "F.Fab")
		)
		(fp_line
			(start -0.67945 0.3048)
			(end -0.67945 -0.305054)
			(stroke
				(width 0.1)
				(type default)
			)
			(layer "F.Fab")
		)
		(fp_line
			(start -0.67945 -0.305054)
			(end -0.12065 -0.305054)
			(stroke
				(width 0.1)
				(type default)
			)
			(layer "F.Fab")
		)
		(pad "1" smd circle
			(at -0.40005 0 180)
			(size 0 0)
			(layers "F.Cu" "F.Mask" "F.Paste")
			(net "GPU_FPGA_EROT_RECOV_N")
		)
		(pad "2" smd circle
			(at 0.40005 0 180)
			(size 0 0)
			(layers "F.Cu" "F.Mask" "F.Paste")
			(net "GND")
		)
	)
)
